# T6G (Grand Teton) — schematic netlist excerpt (pin names and nets, part order shuffled) for the footprints in the layout excerpt that follows; sources: Cadence DE-HDL packaged netlist, KiCad conversion of 04192023_DAF0TMB3IC0_F0TG_MB_C_brd_V02_OCP.brd

R3519  Q_RES  4.7K 5% CHIP  pkg 0402LF  page 247 : A = P3V3_OCP_V3_2 ; B = SMB_OCP_V3_2_3V3AUX_BUF_SCL
PC2086  Q_CAP  1UF 25V 10% X6S  pkg C0402  page 134 : A = P3V3_OCP_VCC_1 ; B = GND

(kicad_pcb
	(version 20260206)
	(generator "pcbnew")
	(generator_version "10.0")
	(general
		(thickness 1.6)
		(legacy_teardrops no)
	)
	(paper "A4")
	(title_block
		(title "04192023_DAF0TMB3IC0_F0TG_MB_C_brd_V02_OCP.brd")
		(comment 1 "Grand Teton / footprints 1124-1125 of 8354")
	)
	(layers
		(0 "F.Cu" signal "TOP")
		(4 "In1.Cu" signal "GND")
		(6 "In2.Cu" signal "IN1")
		(8 "In3.Cu" signal "GND1")
		(10 "In4.Cu" signal "IN2")
		(12 "In5.Cu" signal "GND2")
		(14 "In6.Cu" signal "IN3")
		(16 "In7.Cu" signal "GND3")
		(18 "In8.Cu" signal "VCC")
		(20 "In9.Cu" signal "VCC1")
		(22 "In10.Cu" signal "GND4")
		(24 "In11.Cu" signal "IN4")
		(26 "In12.Cu" signal "GND5")
		(28 "In13.Cu" signal "IN5")
		(30 "In14.Cu" signal "GND6")
		(32 "In15.Cu" signal "IN6")
		(34 "In16.Cu" signal "GND7")
		(2 "B.Cu" signal "BOTTOM")
		(9 "F.Adhes" user "F.Adhesive")
		(11 "B.Adhes" user "B.Adhesive")
		(13 "F.Paste" user "Package Geometry/Pastemask Top")
		(15 "B.Paste" user "Package Geometry/Pastemask Bottom")
		(5 "F.SilkS" user "Ref Des/Silkscreen Top")
		(7 "B.SilkS" user "Ref Des/Silkscreen Bottom")
		(1 "F.Mask" user "Board Geometry/Soldermask Top")
		(3 "B.Mask" user "Board Geometry/Soldermask Bottom")
		(17 "Dwgs.User" user "User.Drawings")
		(19 "Cmts.User" user "User.Comments")
		(21 "Eco1.User" user "User.Eco1")
		(23 "Eco2.User" user "User.Eco2")
		(25 "Edge.Cuts" user "Board Geometry/Outline")
		(27 "Margin" user)
		(31 "F.CrtYd" user "Package Geometry/Place Bound Top")
		(29 "B.CrtYd" user "Package Geometry/Place Bound Bottom")
		(35 "F.Fab" user "Ref Des/Assembly Top")
		(33 "B.Fab" user "Ref Des/Assembly Bottom")
	)
	(footprint ""
		(layer "F.Cu")
		(at 152.849326 -39.02456 180)
		(property "Reference" "R3519"
			(at 0 0 180)
			(layer "F.SilkS")
			(hide yes)
			(effects
				(font
					(size 1.27 1.27)
				)
			)
		)
		(property "Value" ""
			(at 0 0 180)
			(layer "F.Fab")
			(effects
				(font
					(size 1.27 1.27)
				)
			)
		)
		(duplicate_pad_numbers_are_jumpers no)
		(fp_line
			(start 0.7874 0.4064)
			(end -0.7874 0.4064)
			(stroke
				(width 0.1524)
				(type default)
			)
			(layer "F.SilkS")
		)
		(fp_line
			(start 0.7874 -0.4064)
			(end 0.7874 0.4064)
			(stroke
				(width 0.1524)
				(type default)
			)
			(layer "F.SilkS")
		)
		(fp_line
			(start -0.7874 0.4064)
			(end -0.7874 -0.4064)
			(stroke
				(width 0.1524)
				(type default)
			)
			(layer "F.SilkS")
		)
		(fp_line
			(start -0.7874 -0.4064)
			(end 0.7874 -0.4064)
			(stroke
				(width 0.1524)
				(type default)
			)
			(layer "F.SilkS")
		)
		(fp_line
			(start 0.67945 0.3048)
			(end 0.120396 0.3048)
			(stroke
				(width 0.1)
				(type default)
			)
			(layer "F.Fab")
		)
		(fp_line
			(start 0.67945 -0.3048)
			(end 0.67945 0.3048)
			(stroke
				(width 0.1)
				(type default)
			)
			(layer "F.Fab")
		)
		(fp_line
			(start 0.12065 -0.2794)
			(end 0.12065 -0.3048)
			(stroke
				(width 0.1)
				(type default)
			)
			(layer "F.Fab")
		)
		(fp_line
			(start 0.12065 -0.3048)
			(end 0.67945 -0.3048)
			(stroke
				(width 0.1)
				(type default)
			)
			(layer "F.Fab")
		)
		(fp_line
			(start 0.120396 0.3048)
			(end 0.120396 0.2794)
			(stroke
				(width 0.1)
				(type default)
			)
			(layer "F.Fab")
		)
		(fp_line
			(start 0.120396 0.2794)
			(end -0.12065 0.2794)
			(stroke
				(width 0.1)
				(type default)
			)
			(layer "F.Fab")
		)
		(fp_line
			(start -0.12065 0.3048)
			(end -0.67945 0.3048)
			(stroke
				(width 0.1)
				(type default)
			)
			(layer "F.Fab")
		)
		(fp_line
			(start -0.12065 0.2794)
			(end -0.12065 0.3048)
			(stroke
				(width 0.1)
				(type default)
			)
			(layer "F.Fab")
		)
		(fp_line
			(start -0.12065 -0.2794)
			(end 0.12065 -0.2794)
			(stroke
				(width 0.1)
				(type default)
			)
			(layer "F.Fab")
		)
		(fp_line
			(start -0.12065 -0.305054)
			(end -0.12065 -0.2794)
			(stroke
				(width 0.1)
				(type default)
			)
			(layer "F.Fab")
		)
		(fp_line
			(start -0.67945 0.3048)
			(end -0.67945 -0.305054)
			(stroke
				(width 0.1)
				(type default)
			)
			(layer "F.Fab")
		)
		(fp_line
			(start -0.67945 -0.305054)
			(end -0.12065 -0.305054)
			(stroke
				(width 0.1)
				(type default)
			)
			(layer "F.Fab")
		)
		(pad "1" smd circle
			(at -0.40005 0 180)
			(size 0 0)
			(layers "F.Cu" "F.Mask" "F.Paste")
			(net "P3V3_OCP_V3_2")
		)
		(pad "2" smd circle
			(at 0.40005 0 180)
			(size 0 0)
			(layers "F.Cu" "F.Mask" "F.Paste")
			(net "SMB_OCP_V3_2_3V3AUX_BUF_SCL")
		)
	)
	(footprint ""
		(layer "F.Cu")
		(at 434.443632 -107.17403 90)
		(property "Reference" "PC2086"
			(at 0 0 90)
			(layer "F.SilkS")
			(hide yes)
			(effects
				(font
					(size 1.27 1.27)
				)
			)
		)
		(property "Value" ""
			(at 0 0 90)
			(layer "F.Fab")
			(effects
				(font
					(size 1.27 1.27)
				)
			)
		)
		(duplicate_pad_numbers_are_jumpers no)
		(fp_line
			(start 0.7874 -0.4064)
			(end 0.7874 0.4064)
			(stroke
				(width 0.1524)
				(type default)
			)
			(layer "F.SilkS")
		)
		(fp_line
			(start -0.7874 -0.4064)
			(end 0.7874 -0.4064)
			(stroke
				(width 0.1524)
				(type default)
			)
			(layer "F.SilkS")
		)
		(fp_line
			(start 0.7874 0.4064)
			(end -0.7874 0.4064)
			(stroke
				(width 0.1524)
				(type default)
			)
			(layer "F.SilkS")
		)
		(fp_line
			(start -0.7874 0.4064)
			(end -0.7874 -0.4064)
			(stroke
				(width 0.1524)
				(type default)
			)
			(layer "F.SilkS")
		)
		(fp_line
			(start -0.12065 -0.305054)
			(end -0.12065 -0.2794)
			(stroke
				(width 0.1)
				(type default)
			)
			(layer "F.Fab")
		)
		(fp_line
			(start -0.67945 -0.305054)
			(end -0.12065 -0.305054)
			(stroke
				(width 0.1)
				(type default)
			)
			(layer "F.Fab")
		)
		(fp_line
			(start 0.67945 -0.3048)
			(end 0.67945 0.3048)
			(stroke
				(width 0.1)
				(type default)
			)
			(layer "F.Fab")
		)
		(fp_line
			(start 0.12065 -0.3048)
			(end 0.67945 -0.3048)
			(stroke
				(width 0.1)
				(type default)
			)
			(layer "F.Fab")
		)
		(fp_line
			(start 0.12065 -0.2794)
			(end 0.12065 -0.3048)
			(stroke
				(width 0.1)
				(type default)
			)
			(layer "F.Fab")
		)
		(fp_line
			(start -0.12065 -0.2794)
			(end 0.12065 -0.2794)
			(stroke
				(width 0.1)
				(type default)
			)
			(layer "F.Fab")
		)
		(fp_line
			(start 0.120396 0.2794)
			(end -0.12065 0.2794)
			(stroke
				(width 0.1)
				(type default)
			)
			(layer "F.Fab")
		)
		(fp_line
			(start -0.12065 0.2794)
			(end -0.12065 0.3048)
			(stroke
				(width 0.1)
				(type default)
			)
			(layer "F.Fab")
		)
		(fp_line
			(start 0.67945 0.3048)
			(end 0.120396 0.3048)
			(stroke
				(width 0.1)
				(type default)
			)
			(layer "F.Fab")
		)
		(fp_line
			(start 0.120396 0.3048)
			(end 0.120396 0.2794)
			(stroke
				(width 0.1)
				(type default)
			)
			(layer "F.Fab")
		)
		(fp_line
			(start -0.12065 0.3048)
			(end -0.67945 0.3048)
			(stroke
				(width 0.1)
				(type default)
			)
			(layer "F.Fab")
		)
		(fp_line
			(start -0.67945 0.3048)
			(end -0.67945 -0.305054)
			(stroke
				(width 0.1)
				(type default)
			)
			(layer "F.Fab")
		)
		(pad "1" smd circle
			(at -0.40005 0 90)
			(size 0 0)
			(layers "F.Cu" "F.Mask" "F.Paste")
			(net "P3V3_OCP_VCC_1")
		)
		(pad "2" smd circle
			(at 0.40005 0 90)
			(size 0 0)
			(layers "F.Cu" "F.Mask" "F.Paste")
			(net "GND")
		)
	)
)
